# T6G (Grand Teton) — schematic netlist excerpt (pin names and nets, part order shuffled) for the footprints in the layout excerpt that follows; sources: Cadence DE-HDL packaged netlist, KiCad conversion of 04192023_DAF0TMB3IC0_F0TG_MB_C_brd_V02_OCP.brd

PR4523  Q_RES  10M 1% CHIP  pkg 0402LF  page 140 : A = P3V3_OCP_V3_2_R ; B = P3V3_OCP_GATE_2
R543  Q_RES  1K 1% EMPTY  pkg 0402LF  page 55 : A = PVDD11_S3_P1 ; B = I3C_0_SPD_DDRAF_CPU1_R_SDA

(kicad_pcb
	(version 20260206)
	(generator "pcbnew")
	(generator_version "10.0")
	(general
		(thickness 1.6)
		(legacy_teardrops no)
	)
	(paper "A4")
	(title_block
		(title "04192023_DAF0TMB3IC0_F0TG_MB_C_brd_V02_OCP.brd")
		(comment 1 "Grand Teton / footprints 4048-4049 of 8354")
	)
	(layers
		(0 "F.Cu" signal "TOP")
		(4 "In1.Cu" signal "GND")
		(6 "In2.Cu" signal "IN1")
		(8 "In3.Cu" signal "GND1")
		(10 "In4.Cu" signal "IN2")
		(12 "In5.Cu" signal "GND2")
		(14 "In6.Cu" signal "IN3")
		(16 "In7.Cu" signal "GND3")
		(18 "In8.Cu" signal "VCC")
		(20 "In9.Cu" signal "VCC1")
		(22 "In10.Cu" signal "GND4")
		(24 "In11.Cu" signal "IN4")
		(26 "In12.Cu" signal "GND5")
		(28 "In13.Cu" signal "IN5")
		(30 "In14.Cu" signal "GND6")
		(32 "In15.Cu" signal "IN6")
		(34 "In16.Cu" signal "GND7")
		(2 "B.Cu" signal "BOTTOM")
		(9 "F.Adhes" user "F.Adhesive")
		(11 "B.Adhes" user "B.Adhesive")
		(13 "F.Paste" user "Package Geometry/Pastemask Top")
		(15 "B.Paste" user "Package Geometry/Pastemask Bottom")
		(5 "F.SilkS" user "Ref Des/Silkscreen Top")
		(7 "B.SilkS" user "Ref Des/Silkscreen Bottom")
		(1 "F.Mask" user "Board Geometry/Soldermask Top")
		(3 "B.Mask" user "Board Geometry/Soldermask Bottom")
		(17 "Dwgs.User" user "User.Drawings")
		(19 "Cmts.User" user "User.Comments")
		(21 "Eco1.User" user "User.Eco1")
		(23 "Eco2.User" user "User.Eco2")
		(25 "Edge.Cuts" user "Board Geometry/Outline")
		(27 "Margin" user)
		(31 "F.CrtYd" user "Package Geometry/Place Bound Top")
		(29 "B.CrtYd" user "Package Geometry/Place Bound Bottom")
		(35 "F.Fab" user "Ref Des/Assembly Top")
		(33 "B.Fab" user "Ref Des/Assembly Bottom")
	)
	(footprint ""
		(layer "F.Cu")
		(at 45.212 -171.831 180)
		(property "Reference" "R543"
			(at 0 0 180)
			(layer "F.SilkS")
			(hide yes)
			(effects
				(font
					(size 1.27 1.27)
				)
			)
		)
		(property "Value" ""
			(at 0 0 180)
			(layer "F.Fab")
			(effects
				(font
					(size 1.27 1.27)
				)
			)
		)
		(duplicate_pad_numbers_are_jumpers no)
		(fp_line
			(start 0.7874 0.4064)
			(end -0.7874 0.4064)
			(stroke
				(width 0.1524)
				(type default)
			)
			(layer "F.SilkS")
		)
		(fp_line
			(start 0.7874 -0.4064)
			(end 0.7874 0.4064)
			(stroke
				(width 0.1524)
				(type default)
			)
			(layer "F.SilkS")
		)
		(fp_line
			(start -0.7874 0.4064)
			(end -0.7874 -0.4064)
			(stroke
				(width 0.1524)
				(type default)
			)
			(layer "F.SilkS")
		)
		(fp_line
			(start -0.7874 -0.4064)
			(end 0.7874 -0.4064)
			(stroke
				(width 0.1524)
				(type default)
			)
			(layer "F.SilkS")
		)
		(fp_line
			(start 0.67945 0.3048)
			(end 0.120396 0.3048)
			(stroke
				(width 0.1)
				(type default)
			)
			(layer "F.Fab")
		)
		(fp_line
			(start 0.67945 -0.3048)
			(end 0.67945 0.3048)
			(stroke
				(width 0.1)
				(type default)
			)
			(layer "F.Fab")
		)
		(fp_line
			(start 0.12065 -0.2794)
			(end 0.12065 -0.3048)
			(stroke
				(width 0.1)
				(type default)
			)
			(layer "F.Fab")
		)
		(fp_line
			(start 0.12065 -0.3048)
			(end 0.67945 -0.3048)
			(stroke
				(width 0.1)
				(type default)
			)
			(layer "F.Fab")
		)
		(fp_line
			(start 0.120396 0.3048)
			(end 0.120396 0.2794)
			(stroke
				(width 0.1)
				(type default)
			)
			(layer "F.Fab")
		)
		(fp_line
			(start 0.120396 0.2794)
			(end -0.12065 0.2794)
			(stroke
				(width 0.1)
				(type default)
			)
			(layer "F.Fab")
		)
		(fp_line
			(start -0.12065 0.3048)
			(end -0.67945 0.3048)
			(stroke
				(width 0.1)
				(type default)
			)
			(layer "F.Fab")
		)
		(fp_line
			(start -0.12065 0.2794)
			(end -0.12065 0.3048)
			(stroke
				(width 0.1)
				(type default)
			)
			(layer "F.Fab")
		)
		(fp_line
			(start -0.12065 -0.2794)
			(end 0.12065 -0.2794)
			(stroke
				(width 0.1)
				(type default)
			)
			(layer "F.Fab")
		)
		(fp_line
			(start -0.12065 -0.305054)
			(end -0.12065 -0.2794)
			(stroke
				(width 0.1)
				(type default)
			)
			(layer "F.Fab")
		)
		(fp_line
			(start -0.67945 0.3048)
			(end -0.67945 -0.305054)
			(stroke
				(width 0.1)
				(type default)
			)
			(layer "F.Fab")
		)
		(fp_line
			(start -0.67945 -0.305054)
			(end -0.12065 -0.305054)
			(stroke
				(width 0.1)
				(type default)
			)
			(layer "F.Fab")
		)
		(pad "1" smd circle
			(at -0.40005 0 180)
			(size 0 0)
			(layers "F.Cu" "F.Mask" "F.Paste")
			(net "PVDD11_S3_P1")
		)
		(pad "2" smd circle
			(at 0.40005 0 180)
			(size 0 0)
			(layers "F.Cu" "F.Mask" "F.Paste")
			(net "I3C_0_SPD_DDRAF_CPU1_R_SDA")
		)
	)
	(footprint ""
		(layer "F.Cu")
		(at 89.898982 -53.697378)
		(property "Reference" "PR4523"
			(at 0 0 0)
			(layer "F.SilkS")
			(hide yes)
			(effects
				(font
					(size 1.27 1.27)
				)
			)
		)
		(property "Value" ""
			(at 0 0 0)
			(layer "F.Fab")
			(effects
				(font
					(size 1.27 1.27)
				)
			)
		)
		(duplicate_pad_numbers_are_jumpers no)
		(fp_line
			(start -0.7874 -0.4064)
			(end 0.7874 -0.4064)
			(stroke
				(width 0.1524)
				(type default)
			)
			(layer "F.SilkS")
		)
		(fp_line
			(start -0.7874 0.4064)
			(end -0.7874 -0.4064)
			(stroke
				(width 0.1524)
				(type default)
			)
			(layer "F.SilkS")
		)
		(fp_line
			(start 0.7874 -0.4064)
			(end 0.7874 0.4064)
			(stroke
				(width 0.1524)
				(type default)
			)
			(layer "F.SilkS")
		)
		(fp_line
			(start 0.7874 0.4064)
			(end -0.7874 0.4064)
			(stroke
				(width 0.1524)
				(type default)
			)
			(layer "F.SilkS")
		)
		(fp_line
			(start -0.67945 -0.305054)
			(end -0.12065 -0.305054)
			(stroke
				(width 0.1)
				(type default)
			)
			(layer "F.Fab")
		)
		(fp_line
			(start -0.67945 0.3048)
			(end -0.67945 -0.305054)
			(stroke
				(width 0.1)
				(type default)
			)
			(layer "F.Fab")
		)
		(fp_line
			(start -0.12065 -0.305054)
			(end -0.12065 -0.2794)
			(stroke
				(width 0.1)
				(type default)
			)
			(layer "F.Fab")
		)
		(fp_line
			(start -0.12065 -0.2794)
			(end 0.12065 -0.2794)
			(stroke
				(width 0.1)
				(type default)
			)
			(layer "F.Fab")
		)
		(fp_line
			(start -0.12065 0.2794)
			(end -0.12065 0.3048)
			(stroke
				(width 0.1)
				(type default)
			)
			(layer "F.Fab")
		)
		(fp_line
			(start -0.12065 0.3048)
			(end -0.67945 0.3048)
			(stroke
				(width 0.1)
				(type default)
			)
			(layer "F.Fab")
		)
		(fp_line
			(start 0.120396 0.2794)
			(end -0.12065 0.2794)
			(stroke
				(width 0.1)
				(type default)
			)
			(layer "F.Fab")
		)
		(fp_line
			(start 0.120396 0.3048)
			(end 0.120396 0.2794)
			(stroke
				(width 0.1)
				(type default)
			)
			(layer "F.Fab")
		)
		(fp_line
			(start 0.12065 -0.3048)
			(end 0.67945 -0.3048)
			(stroke
				(width 0.1)
				(type default)
			)
			(layer "F.Fab")
		)
		(fp_line
			(start 0.12065 -0.2794)
			(end 0.12065 -0.3048)
			(stroke
				(width 0.1)
				(type default)
			)
			(layer "F.Fab")
		)
		(fp_line
			(start 0.67945 -0.3048)
			(end 0.67945 0.3048)
			(stroke
				(width 0.1)
				(type default)
			)
			(layer "F.Fab")
		)
		(fp_line
			(start 0.67945 0.3048)
			(end 0.120396 0.3048)
			(stroke
				(width 0.1)
				(type default)
			)
			(layer "F.Fab")
		)
		(pad "1" smd circle
			(at -0.40005 0)
			(size 0 0)
			(layers "F.Cu" "F.Mask" "F.Paste")
			(net "P3V3_OCP_V3_2_R")
		)
		(pad "2" smd circle
			(at 0.40005 0)
			(size 0 0)
			(layers "F.Cu" "F.Mask" "F.Paste")
			(net "P3V3_OCP_GATE_2")
		)
	)
)
